FILE_TYPE = MACRO_DRAWING;
SET COLOR_WIRE YELLOW;
SET COLOR_PROP MONO;
SET COLOR_DOT WHITE;
SET COLOR_ARC YELLOW;
SET COLOR_BODY GREEN;
SET COLOR_NOTE MONO;
SET PROP_DISPLAY VALUE;
SET PAGE_NUMBER P97;
FORCEADD OFFPAGE..3
(-275 4225);
FORCEPROP 2 LAST $XR0 55 
J 0
(-61 4225);
DISPLAY 0.638298 (-61 4225);
PAINT MONO (-61 4225);
FORCEPROP 2 LAST CDS_LIB mstr_standard
J 0
(-275 4225);
PAINT ORANGE (-275 4225);
DISPLAY INVISIBLE (-275 4225);
FORCEPROP 1 LAST OFFPAGE TRUE
J 0
(50 4100);
PAINT GREEN (50 4100);
DISPLAY INVISIBLE (50 4100);
FORCEPROP 1 LAST COMMENT_BODY TRUE
J 0
(-325 4125);
DISPLAY 1.170213 (-325 4125);
PAINT PEACH (-325 4125);
DISPLAY INVISIBLE (-325 4125);
FORCEPROP 2 LAST PATH I22
J 0
(-50 4275);
DISPLAY 1.021277 (-50 4275);
PAINT ORANGE (-50 4275);
DISPLAY INVISIBLE (-50 4275);
FORCEADD RES..1
(-2000 4225);
FORCEPROP 1 LASTPIN (-2100 4225) $PN 1
J 0
(-2088 4237);
DISPLAY 0.617021 (-2088 4237);
PAINT WHITE (-2088 4237);
FORCEPROP 1 LAST TOLERANCE 5%
J 0
(-2075 4175);
DISPLAY 0.617021 (-2075 4175);
PAINT SKYBLUE (-2075 4175);
FORCEPROP 1 LAST PART_NUMBER G21497-005
J 0
(-2150 4125);
DISPLAY 0.617021 (-2150 4125);
PAINT BLUE (-2150 4125);
FORCEPROP 1 LAST VALUE 0.0
J 2
(-2100 4175);
DISPLAY 0.617021 (-2100 4175);
PAINT SKYBLUE (-2100 4175);
FORCEPROP 1 LAST PACK_TYPE 0402
J 0
(-1975 4175);
DISPLAY 0.617021 (-1975 4175);
PAINT SKYBLUE (-1975 4175);
FORCEPROP 1 LAST MATERIAL CHIP
J 0
(-1800 4125);
DISPLAY 0.617021 (-1800 4125);
PAINT SKYBLUE (-1800 4125);
FORCEPROP 1 LAST WATTAGE 1/16W
J 2
(-1625 4175);
DISPLAY 0.617021 (-1625 4175);
PAINT SKYBLUE (-1625 4175);
FORCEPROP 1 LAST LOCATION R3D18
J 0
(-2050 4275);
DISPLAY 0.617021 (-2050 4275);
PAINT AQUA (-2050 4275);
FORCEPROP 1 LASTPIN (-1900 4225) $PN 2
J 0
(-1938 4237);
DISPLAY 0.617021 (-1938 4237);
PAINT WHITE (-1938 4237);
FORCEPROP 2 LAST BOM_COST PROC_SIDEBAND
J 0
(-2000 4225);
PAINT WHITE (-2000 4225);
DISPLAY INVISIBLE (-2000 4225);
FORCEPROP 2 LAST CDS_LIB mstr_discrete
J 0
(-2000 4225);
PAINT ORANGE (-2000 4225);
DISPLAY INVISIBLE (-2000 4225);
FORCEPROP 2 LAST CDS_SEC 1
J 0
(-2050 4425);
DISPLAY 1.404255 (-2050 4425);
PAINT ORANGE (-2050 4425);
DISPLAY INVISIBLE (-2050 4425);
FORCEPROP 2 LAST $SEC 1
J 0
(-2050 4425);
DISPLAY 0.936170 (-2050 4425);
PAINT MONO (-2050 4425);
DISPLAY INVISIBLE (-2050 4425);
FORCEPROP 2 LAST CDS_LOCATION R3D18
J 0
(-2050 4275);
DISPLAY 0.617021 (-2050 4275);
PAINT AQUA (-2050 4275);
DISPLAY INVISIBLE (-2050 4275);
FORCEPROP 1 LAST PATH I33
J 0
(-2050 4375);
DISPLAY 0.978723 (-2050 4375);
PAINT WHITE (-2050 4375);
DISPLAY INVISIBLE (-2050 4375);
FORCEPROP 2 LAST ROOM PROC_SIDEBAND
J 0
(-2050 4375);
PAINT WHITE (-2050 4375);
DISPLAY INVISIBLE (-2050 4375);
FORCEADD OFFPAGE..6
(-3400 4225);
FORCEPROP 2 LAST $XR1 157 
J 0
(-3649 4261);
DISPLAY 0.638298 (-3649 4261);
PAINT MONO (-3649 4261);
FORCEPROP 2 LAST $XR0 21 
J 0
(-3649 4225);
DISPLAY 0.638298 (-3649 4225);
PAINT MONO (-3649 4225);
FORCEPROP 2 LAST CDS_LIB mstr_standard
J 0
(-3400 4225);
PAINT ORANGE (-3400 4225);
DISPLAY INVISIBLE (-3400 4225);
FORCEPROP 1 LAST OFFPAGE TRUE
J 0
(-3075 4100);
PAINT GREEN (-3075 4100);
DISPLAY INVISIBLE (-3075 4100);
FORCEPROP 1 LAST COMMENT_BODY TRUE
J 0
(-3300 4150);
DISPLAY 1.170213 (-3300 4150);
PAINT PEACH (-3300 4150);
DISPLAY INVISIBLE (-3300 4150);
FORCEPROP 2 LAST PATH I34
J 0
(-3625 4275);
DISPLAY 1.021277 (-3625 4275);
PAINT ORANGE (-3625 4275);
DISPLAY INVISIBLE (-3625 4275);
FORCEADD PVCCIO_CPU0..1
(-2700 4775);
FORCEPROP 3 LASTPIN (-2700 4725) SIG_NAME PVCCIO_CPU0\g
J 0
(-2690 4735);
DISPLAY 0.659574 (-2690 4735);
PAINT MONO (-2690 4735);
DISPLAY INVISIBLE (-2690 4735);
FORCEPROP 1 LAST VOLTAGE 1.1V
J 0
(-2745 4732);
DISPLAY 0.340426 (-2745 4732);
PAINT SKYBLUE (-2745 4732);
DISPLAY INVISIBLE (-2745 4732);
FORCEPROP 2 LAST CDS_LIB mstr_symbols
J 0
(-2700 4775);
PAINT ORANGE (-2700 4775);
DISPLAY INVISIBLE (-2700 4775);
FORCEPROP 1 LAST BODY_TYPE PLUMBING
J 0
(-2745 4732);
DISPLAY 0.340426 (-2745 4732);
PAINT GREEN (-2745 4732);
DISPLAY INVISIBLE (-2745 4732);
FORCEPROP 1 LAST PATH I41
J 0
(-2650 4800);
DISPLAY 0.872340 (-2650 4800);
PAINT AQUA (-2650 4800);
DISPLAY INVISIBLE (-2650 4800);
FORCEPROP 1 LAST HDL_POWER PVCCIO_CPU0
J 1
(-2700 4825);
DISPLAY 0.872340 (-2700 4825);
PAINT GREEN (-2700 4825);
DISPLAY INVISIBLE (-2700 4825);
FORCEADD RES..2
(-2700 4525);
FORCEPROP 1 LAST LOCATION R4R4
J 0
(-2655 4650);
DISPLAY 0.617021 (-2655 4650);
PAINT AQUA (-2655 4650);
FORCEPROP 1 LAST PART_NUMBER G21796-009
J 0
(-2660 4400);
DISPLAY 0.617021 (-2660 4400);
PAINT BLUE (-2660 4400);
FORCEPROP 1 LAST VALUE 150.0
J 0
(-2655 4600);
DISPLAY 0.617021 (-2655 4600);
PAINT SKYBLUE (-2655 4600);
FORCEPROP 1 LAST TOLERANCE 1%
J 0
(-2655 4550);
DISPLAY 0.617021 (-2655 4550);
PAINT SKYBLUE (-2655 4550);
FORCEPROP 1 LAST PACK_TYPE 0402
J 0
(-2660 4350);
DISPLAY 0.617021 (-2660 4350);
PAINT SKYBLUE (-2660 4350);
FORCEPROP 1 LAST MATERIAL CHIP
J 0
(-2660 4450);
DISPLAY 0.617021 (-2660 4450);
PAINT SKYBLUE (-2660 4450);
FORCEPROP 1 LAST WATTAGE 1/16W
J 0
(-2660 4500);
DISPLAY 0.617021 (-2660 4500);
PAINT SKYBLUE (-2660 4500);
FORCEPROP 1 LASTPIN (-2700 4425) $PN 2
J 0
(-2695 4435);
DISPLAY 0.617021 (-2695 4435);
PAINT WHITE (-2695 4435);
FORCEPROP 1 LASTPIN (-2700 4625) $PN 1
J 0
(-2695 4587);
DISPLAY 0.617021 (-2695 4587);
PAINT WHITE (-2695 4587);
FORCEPROP 2 LAST CDS_LIB mstr_discrete
J 0
(-2700 4525);
PAINT ORANGE (-2700 4525);
DISPLAY INVISIBLE (-2700 4525);
FORCEPROP 2 LAST CDS_SEC 1
J 0
(-2650 4750);
DISPLAY 1.404255 (-2650 4750);
PAINT ORANGE (-2650 4750);
DISPLAY INVISIBLE (-2650 4750);
FORCEPROP 2 LAST $SEC 1
J 0
(-2650 4750);
DISPLAY 0.936170 (-2650 4750);
PAINT MONO (-2650 4750);
DISPLAY INVISIBLE (-2650 4750);
FORCEPROP 2 LAST CDS_LOCATION R4R4
J 0
(-2655 4650);
DISPLAY 0.617021 (-2655 4650);
PAINT AQUA (-2655 4650);
DISPLAY INVISIBLE (-2655 4650);
FORCEPROP 1 LAST PATH I42
J 0
(-2650 4700);
DISPLAY 0.978723 (-2650 4700);
PAINT WHITE (-2650 4700);
DISPLAY INVISIBLE (-2650 4700);
FORCEPROP 2 LAST ROOM PROC_SIDEBAND
J 0
(-2655 4690);
DISPLAY 0.787234 (-2655 4690);
PAINT WHITE (-2655 4690);
DISPLAY INVISIBLE (-2655 4690);
FORCEADD RES..2
(-1200 4525);
FORCEPROP 1 LAST PART_NUMBER G21796-009
J 0
(-1160 4400);
DISPLAY 0.617021 (-1160 4400);
PAINT BLUE (-1160 4400);
FORCEPROP 1 LAST LOCATION R7P20
J 0
(-1155 4650);
DISPLAY 0.617021 (-1155 4650);
PAINT AQUA (-1155 4650);
FORCEPROP 1 LAST VALUE 150.0
J 0
(-1155 4600);
DISPLAY 0.617021 (-1155 4600);
PAINT SKYBLUE (-1155 4600);
FORCEPROP 1 LAST TOLERANCE 1%
J 0
(-1155 4550);
DISPLAY 0.617021 (-1155 4550);
PAINT SKYBLUE (-1155 4550);
FORCEPROP 1 LAST WATTAGE 1/16W
J 0
(-1160 4500);
DISPLAY 0.617021 (-1160 4500);
PAINT SKYBLUE (-1160 4500);
FORCEPROP 1 LASTPIN (-1200 4425) $PN 2
J 0
(-1195 4435);
DISPLAY 0.617021 (-1195 4435);
PAINT WHITE (-1195 4435);
FORCEPROP 1 LASTPIN (-1200 4625) $PN 1
J 0
(-1195 4587);
DISPLAY 0.617021 (-1195 4587);
PAINT WHITE (-1195 4587);
FORCEPROP 1 LAST PACK_TYPE 0402
J 0
(-1160 4350);
DISPLAY 0.617021 (-1160 4350);
PAINT SKYBLUE (-1160 4350);
FORCEPROP 1 LAST MATERIAL CHIP
J 0
(-1160 4450);
DISPLAY 0.617021 (-1160 4450);
PAINT SKYBLUE (-1160 4450);
FORCEPROP 2 LAST CDS_LIB mstr_discrete
J 0
(-1200 4525);
PAINT ORANGE (-1200 4525);
DISPLAY INVISIBLE (-1200 4525);
FORCEPROP 2 LAST CDS_SEC 1
J 0
(-1150 4750);
DISPLAY 1.404255 (-1150 4750);
PAINT ORANGE (-1150 4750);
DISPLAY INVISIBLE (-1150 4750);
FORCEPROP 2 LAST $SEC 1
J 0
(-1150 4750);
DISPLAY 0.936170 (-1150 4750);
PAINT MONO (-1150 4750);
DISPLAY INVISIBLE (-1150 4750);
FORCEPROP 2 LAST CDS_LOCATION R7P20
J 0
(-1155 4650);
DISPLAY 0.617021 (-1155 4650);
PAINT AQUA (-1155 4650);
DISPLAY INVISIBLE (-1155 4650);
FORCEPROP 1 LAST PATH I44
J 0
(-1150 4700);
DISPLAY 0.978723 (-1150 4700);
PAINT WHITE (-1150 4700);
DISPLAY INVISIBLE (-1150 4700);
FORCEPROP 2 LAST ROOM PROC_SIDEBAND
J 0
(-1155 4690);
DISPLAY 0.787234 (-1155 4690);
PAINT WHITE (-1155 4690);
DISPLAY INVISIBLE (-1155 4690);
FORCEADD PVCCIO_CPU0..1
(-3100 1625);
FORCEPROP 3 LASTPIN (-3100 1575) SIG_NAME PVCCIO_CPU0\g
J 0
(-3090 1585);
DISPLAY 0.659574 (-3090 1585);
PAINT MONO (-3090 1585);
DISPLAY INVISIBLE (-3090 1585);
FORCEPROP 1 LAST VOLTAGE 1.1V
J 0
(-3145 1582);
DISPLAY 0.340426 (-3145 1582);
PAINT SKYBLUE (-3145 1582);
DISPLAY INVISIBLE (-3145 1582);
FORCEPROP 2 LAST CDS_LIB mstr_symbols
J 0
(-3100 1625);
PAINT ORANGE (-3100 1625);
DISPLAY INVISIBLE (-3100 1625);
FORCEPROP 1 LAST BODY_TYPE PLUMBING
J 0
(-3145 1582);
DISPLAY 0.340426 (-3145 1582);
PAINT GREEN (-3145 1582);
DISPLAY INVISIBLE (-3145 1582);
FORCEPROP 1 LAST PATH I71
J 0
(-3050 1650);
DISPLAY 0.872340 (-3050 1650);
PAINT AQUA (-3050 1650);
DISPLAY INVISIBLE (-3050 1650);
FORCEPROP 1 LAST HDL_POWER PVCCIO_CPU0
J 1
(-3100 1675);
DISPLAY 0.872340 (-3100 1675);
PAINT GREEN (-3100 1675);
DISPLAY INVISIBLE (-3100 1675);
FORCEADD RES..1
(-2625 1425);
FORCEPROP 1 LAST LOCATION R4P21
J 0
(-2675 1475);
DISPLAY 0.617021 (-2675 1475);
PAINT AQUA (-2675 1475);
FORCEPROP 1 LAST PART_NUMBER G21796-294
J 0
(-3050 1375);
DISPLAY 0.617021 (-3050 1375);
PAINT BLUE (-3050 1375);
FORCEPROP 1 LAST VALUE 240
J 2
(-2675 1375);
DISPLAY 0.617021 (-2675 1375);
PAINT SKYBLUE (-2675 1375);
FORCEPROP 1 LAST TOLERANCE 1.0%
J 0
(-2575 1375);
DISPLAY 0.617021 (-2575 1375);
PAINT SKYBLUE (-2575 1375);
FORCEPROP 1 LAST PACK_TYPE 0402
J 0
(-2250 1375);
DISPLAY 0.617021 (-2250 1375);
PAINT SKYBLUE (-2250 1375);
FORCEPROP 1 LAST WATTAGE 1/16W
J 2
(-2300 1375);
DISPLAY 0.617021 (-2300 1375);
PAINT SKYBLUE (-2300 1375);
FORCEPROP 1 LASTPIN (-2525 1425) $PN 2
J 0
(-2563 1437);
DISPLAY 0.617021 (-2563 1437);
PAINT WHITE (-2563 1437);
FORCEPROP 1 LASTPIN (-2725 1425) $PN 1
J 0
(-2713 1437);
DISPLAY 0.617021 (-2713 1437);
PAINT WHITE (-2713 1437);
FORCEPROP 1 LAST MATERIAL CHIP
J 0
(-2150 1375);
DISPLAY 0.617021 (-2150 1375);
PAINT SKYBLUE (-2150 1375);
FORCEPROP 2 LAST SEC_TYPE 0402
J 0
(-2675 1625);
DISPLAY 1.021277 (-2675 1625);
PAINT ORANGE (-2675 1625);
DISPLAY INVISIBLE (-2675 1625);
FORCEPROP 2 LAST CDS_LIB mstr_discrete
J 0
(-2625 1425);
PAINT ORANGE (-2625 1425);
DISPLAY INVISIBLE (-2625 1425);
FORCEPROP 0 LAST BOM_COST PROC_SIDEBAND
J 0
(-2675 1675);
DISPLAY 1.021277 (-2675 1675);
PAINT WHITE (-2675 1675);
DISPLAY INVISIBLE (-2675 1675);
FORCEPROP 2 LAST SEC 1
J 0
(-2675 1625);
DISPLAY 0.680851 (-2675 1625);
PAINT MONO (-2675 1625);
DISPLAY INVISIBLE (-2675 1625);
FORCEPROP 2 LAST CDS_LOCATION R4P21
J 0
(-2675 1475);
DISPLAY 0.617021 (-2675 1475);
PAINT AQUA (-2675 1475);
DISPLAY INVISIBLE (-2675 1475);
FORCEPROP 1 LAST PATH I72
J 0
(-2675 1575);
DISPLAY 0.978723 (-2675 1575);
PAINT WHITE (-2675 1575);
DISPLAY INVISIBLE (-2675 1575);
FORCEPROP 0 LAST ROOM PROC_SIDEBAND
J 0
(-2675 1575);
DISPLAY 1.021277 (-2675 1575);
PAINT WHITE (-2675 1575);
DISPLAY INVISIBLE (-2675 1575);
FORCEADD OFFPAGE..5
R 2
(-1600 1425);
FORCEPROP 2 LAST $XR0 21 
J 0
(-1411 1425);
DISPLAY 0.638298 (-1411 1425);
PAINT MONO (-1411 1425);
FORCEPROP 2 LAST CDS_LIB mstr_standard
J 0
(-1600 1425);
PAINT ORANGE (-1600 1425);
DISPLAY INVISIBLE (-1600 1425);
FORCEPROP 1 LAST OFFPAGE TRUE
J 2
(-1925 1300);
PAINT GREEN (-1925 1300);
DISPLAY INVISIBLE (-1925 1300);
FORCEPROP 1 LAST COMMENT_BODY TRUE
J 2
(-1700 1350);
DISPLAY 1.170213 (-1700 1350);
PAINT PEACH (-1700 1350);
DISPLAY INVISIBLE (-1700 1350);
FORCEPROP 2 LAST PATH I74
J 0
(-1425 1500);
DISPLAY 1.021277 (-1425 1500);
PAINT ORANGE (-1425 1500);
DISPLAY INVISIBLE (-1425 1500);
FORCEADD RES..1
(-2600 800);
FORCEPROP 1 LAST LOCATION R4C10
J 0
(-2650 850);
DISPLAY 0.617021 (-2650 850);
PAINT AQUA (-2650 850);
FORCEPROP 1 LAST PART_NUMBER G21796-294
J 0
(-3025 750);
DISPLAY 0.617021 (-3025 750);
PAINT BLUE (-3025 750);
FORCEPROP 1 LAST VALUE 240
J 2
(-2650 750);
DISPLAY 0.617021 (-2650 750);
PAINT SKYBLUE (-2650 750);
FORCEPROP 1 LAST TOLERANCE 1.0%
J 0
(-2550 750);
DISPLAY 0.617021 (-2550 750);
PAINT SKYBLUE (-2550 750);
FORCEPROP 1 LAST PACK_TYPE 0402
J 0
(-2225 750);
DISPLAY 0.617021 (-2225 750);
PAINT SKYBLUE (-2225 750);
FORCEPROP 1 LAST MATERIAL CHIP
J 0
(-2125 750);
DISPLAY 0.617021 (-2125 750);
PAINT SKYBLUE (-2125 750);
FORCEPROP 1 LAST WATTAGE 1/16W
J 2
(-2275 750);
DISPLAY 0.617021 (-2275 750);
PAINT SKYBLUE (-2275 750);
FORCEPROP 1 LASTPIN (-2500 800) $PN 2
J 0
(-2538 812);
DISPLAY 0.617021 (-2538 812);
PAINT WHITE (-2538 812);
FORCEPROP 1 LASTPIN (-2700 800) $PN 1
J 0
(-2688 812);
DISPLAY 0.617021 (-2688 812);
PAINT WHITE (-2688 812);
FORCEPROP 2 LAST SEC_TYPE 0402
J 0
(-2650 1000);
DISPLAY 1.021277 (-2650 1000);
PAINT ORANGE (-2650 1000);
DISPLAY INVISIBLE (-2650 1000);
FORCEPROP 2 LAST CDS_LIB mstr_discrete
J 0
(-2600 800);
PAINT ORANGE (-2600 800);
DISPLAY INVISIBLE (-2600 800);
FORCEPROP 0 LAST BOM_COST PROC_SIDEBAND
J 0
(-2650 1050);
DISPLAY 1.021277 (-2650 1050);
PAINT WHITE (-2650 1050);
DISPLAY INVISIBLE (-2650 1050);
FORCEPROP 2 LAST SEC 1
J 0
(-2650 1000);
DISPLAY 0.680851 (-2650 1000);
PAINT MONO (-2650 1000);
DISPLAY INVISIBLE (-2650 1000);
FORCEPROP 2 LAST CDS_LOCATION R4C10
J 0
(-2650 850);
DISPLAY 0.617021 (-2650 850);
PAINT AQUA (-2650 850);
DISPLAY INVISIBLE (-2650 850);
FORCEPROP 1 LAST PATH I76
J 0
(-2650 950);
DISPLAY 0.978723 (-2650 950);
PAINT WHITE (-2650 950);
DISPLAY INVISIBLE (-2650 950);
FORCEPROP 0 LAST ROOM PROC_SIDEBAND
J 0
(-2650 950);
DISPLAY 1.021277 (-2650 950);
PAINT WHITE (-2650 950);
DISPLAY INVISIBLE (-2650 950);
FORCEADD OFFPAGE..5
R 2
(-1575 800);
FORCEPROP 2 LAST $XR0 55 
J 0
(-1386 800);
DISPLAY 0.638298 (-1386 800);
PAINT MONO (-1386 800);
FORCEPROP 2 LAST CDS_LIB mstr_standard
J 0
(-1575 800);
PAINT ORANGE (-1575 800);
DISPLAY INVISIBLE (-1575 800);
FORCEPROP 1 LAST OFFPAGE TRUE
J 2
(-1900 675);
PAINT GREEN (-1900 675);
DISPLAY INVISIBLE (-1900 675);
FORCEPROP 1 LAST COMMENT_BODY TRUE
J 2
(-1675 725);
DISPLAY 1.170213 (-1675 725);
PAINT PEACH (-1675 725);
DISPLAY INVISIBLE (-1675 725);
FORCEPROP 2 LAST PATH I77
J 0
(-1400 875);
DISPLAY 1.021277 (-1400 875);
PAINT ORANGE (-1400 875);
DISPLAY INVISIBLE (-1400 875);
FORCEADD PVCCIO_CPU1..1
(-3075 1000);
FORCEPROP 3 LASTPIN (-3075 950) SIG_NAME PVCCIO_CPU1\g
J 0
(-3065 960);
DISPLAY 0.659574 (-3065 960);
PAINT MONO (-3065 960);
DISPLAY INVISIBLE (-3065 960);
FORCEPROP 1 LAST VOLTAGE 1.1V
J 0
(-3120 957);
DISPLAY 0.340426 (-3120 957);
PAINT SKYBLUE (-3120 957);
DISPLAY INVISIBLE (-3120 957);
FORCEPROP 2 LAST CDS_LIB mstr_symbols
J 0
(-3075 1000);
PAINT ORANGE (-3075 1000);
DISPLAY INVISIBLE (-3075 1000);
FORCEPROP 1 LAST BODY_TYPE PLUMBING
J 0
(-3120 957);
DISPLAY 0.340426 (-3120 957);
PAINT GREEN (-3120 957);
DISPLAY INVISIBLE (-3120 957);
FORCEPROP 1 LAST PATH I78
J 0
(-3025 1025);
DISPLAY 0.872340 (-3025 1025);
PAINT AQUA (-3025 1025);
DISPLAY INVISIBLE (-3025 1025);
FORCEPROP 1 LAST HDL_POWER PVCCIO_CPU1
J 1
(-3075 1050);
DISPLAY 0.872340 (-3075 1050);
PAINT GREEN (-3075 1050);
DISPLAY INVISIBLE (-3075 1050);
FORCEADD RES..1
(-2375 3175);
FORCEPROP 1 LAST PART_NUMBER G21796-016
J 0
(-2425 3275);
DISPLAY 0.617021 (-2425 3275);
PAINT BLUE (-2425 3275);
FORCEPROP 1 LAST LOCATION R4P5
J 0
(-2425 3225);
DISPLAY 0.617021 (-2425 3225);
PAINT AQUA (-2425 3225);
FORCEPROP 1 LAST VALUE 10.0K
J 2
(-2400 3075);
DISPLAY 0.617021 (-2400 3075);
PAINT SKYBLUE (-2400 3075);
FORCEPROP 1 LAST TOLERANCE 1%
J 0
(-2375 3075);
DISPLAY 0.617021 (-2375 3075);
PAINT SKYBLUE (-2375 3075);
FORCEPROP 1 LAST PACK_TYPE 0402
J 0
(-2125 3025);
DISPLAY 0.617021 (-2125 3025);
PAINT SKYBLUE (-2125 3025);
FORCEPROP 1 LAST MATERIAL CHIP
J 0
(-2375 3025);
DISPLAY 0.617021 (-2375 3025);
PAINT SKYBLUE (-2375 3025);
FORCEPROP 1 LAST WATTAGE 1/16W
J 2
(-2400 3025);
DISPLAY 0.617021 (-2400 3025);
PAINT SKYBLUE (-2400 3025);
FORCEPROP 1 LASTPIN (-2275 3175) $PN 2
J 0
(-2313 3187);
DISPLAY 0.617021 (-2313 3187);
PAINT ORANGE (-2313 3187);
FORCEPROP 1 LASTPIN (-2475 3175) $PN 1
J 0
(-2463 3187);
DISPLAY 0.617021 (-2463 3187);
PAINT ORANGE (-2463 3187);
FORCEPROP 2 LAST CDS_LIB mstr_discrete
J 0
(-2375 3175);
PAINT ORANGE (-2375 3175);
DISPLAY INVISIBLE (-2375 3175);
FORCEPROP 2 LAST SEC_TYPE 0402
J 0
(-2425 3375);
DISPLAY 1.021277 (-2425 3375);
PAINT ORANGE (-2425 3375);
DISPLAY INVISIBLE (-2425 3375);
FORCEPROP 2 LAST SEC 1
J 0
(-2425 3375);
DISPLAY 0.680851 (-2425 3375);
PAINT MONO (-2425 3375);
DISPLAY INVISIBLE (-2425 3375);
FORCEPROP 2 LAST CDS_LOCATION R4P5
J 0
(-2425 3225);
DISPLAY 0.617021 (-2425 3225);
PAINT AQUA (-2425 3225);
DISPLAY INVISIBLE (-2425 3225);
FORCEPROP 1 LAST PATH I80
J 0
(-2425 3325);
DISPLAY 0.978723 (-2425 3325);
PAINT WHITE (-2425 3325);
DISPLAY INVISIBLE (-2425 3325);
FORCEPROP 0 LAST ROOM CPU0
J 0
(-2425 3375);
DISPLAY 1.021277 (-2425 3375);
PAINT ORANGE (-2425 3375);
DISPLAY INVISIBLE (-2425 3375);
FORCEADD RES..1
(-2375 2825);
FORCEPROP 1 LAST LOCATION R7P13
J 0
(-2425 2875);
DISPLAY 0.617021 (-2425 2875);
PAINT AQUA (-2425 2875);
FORCEPROP 1 LAST PART_NUMBER G21796-016
J 0
(-2425 2925);
DISPLAY 0.617021 (-2425 2925);
PAINT BLUE (-2425 2925);
FORCEPROP 1 LAST VALUE 10.0K
J 2
(-2400 2725);
DISPLAY 0.617021 (-2400 2725);
PAINT SKYBLUE (-2400 2725);
FORCEPROP 1 LAST TOLERANCE 1%
J 0
(-2375 2725);
DISPLAY 0.617021 (-2375 2725);
PAINT SKYBLUE (-2375 2725);
FORCEPROP 1 LAST PACK_TYPE 0402
J 0
(-2125 2675);
DISPLAY 0.617021 (-2125 2675);
PAINT SKYBLUE (-2125 2675);
FORCEPROP 1 LAST MATERIAL CHIP
J 0
(-2375 2675);
DISPLAY 0.617021 (-2375 2675);
PAINT SKYBLUE (-2375 2675);
FORCEPROP 1 LAST WATTAGE 1/16W
J 2
(-2400 2675);
DISPLAY 0.617021 (-2400 2675);
PAINT SKYBLUE (-2400 2675);
FORCEPROP 1 LASTPIN (-2275 2825) $PN 2
J 0
(-2313 2837);
DISPLAY 0.617021 (-2313 2837);
PAINT ORANGE (-2313 2837);
FORCEPROP 1 LASTPIN (-2475 2825) $PN 1
J 0
(-2463 2837);
DISPLAY 0.617021 (-2463 2837);
PAINT ORANGE (-2463 2837);
FORCEPROP 2 LAST CDS_LIB mstr_discrete
J 0
(-2375 2825);
PAINT ORANGE (-2375 2825);
DISPLAY INVISIBLE (-2375 2825);
FORCEPROP 2 LAST SEC_TYPE 0402
J 0
(-2425 3025);
DISPLAY 1.021277 (-2425 3025);
PAINT ORANGE (-2425 3025);
DISPLAY INVISIBLE (-2425 3025);
FORCEPROP 2 LAST SEC 1
J 0
(-2425 3025);
DISPLAY 0.680851 (-2425 3025);
PAINT MONO (-2425 3025);
DISPLAY INVISIBLE (-2425 3025);
FORCEPROP 2 LAST CDS_LOCATION R7P13
J 0
(-2425 2875);
DISPLAY 0.617021 (-2425 2875);
PAINT AQUA (-2425 2875);
DISPLAY INVISIBLE (-2425 2875);
FORCEPROP 1 LAST PATH I81
J 0
(-2425 2975);
DISPLAY 0.978723 (-2425 2975);
PAINT WHITE (-2425 2975);
DISPLAY INVISIBLE (-2425 2975);
FORCEPROP 0 LAST ROOM CPU1
J 0
(-2425 3025);
DISPLAY 1.021277 (-2425 3025);
PAINT ORANGE (-2425 3025);
DISPLAY INVISIBLE (-2425 3025);
FORCEADD GND..1
(-3075 2425);
FORCEPROP 3 LASTPIN (-3075 2475) SIG_NAME GND\g
J 0
(-3065 2485);
DISPLAY 0.659574 (-3065 2485);
PAINT MONO (-3065 2485);
DISPLAY INVISIBLE (-3065 2485);
FORCEPROP 1 LAST VOLTAGE 0.0V
J 0
(-3120 2382);
DISPLAY 0.340426 (-3120 2382);
PAINT SKYBLUE (-3120 2382);
DISPLAY INVISIBLE (-3120 2382);
FORCEPROP 1 LAST SIZE 1B
J 0
(-3000 2375);
DISPLAY 1.170213 (-3000 2375);
PAINT AQUA (-3000 2375);
DISPLAY INVISIBLE (-3000 2375);
FORCEPROP 2 LAST CDS_LIB mstr_symbols
J 0
(-3075 2425);
PAINT ORANGE (-3075 2425);
DISPLAY INVISIBLE (-3075 2425);
FORCEPROP 1 LAST BODY_TYPE PLUMBING
J 0
(-3120 2382);
DISPLAY 0.340426 (-3120 2382);
PAINT GREEN (-3120 2382);
DISPLAY INVISIBLE (-3120 2382);
FORCEPROP 1 LAST PATH I82
J 0
(-3000 2425);
DISPLAY 0.872340 (-3000 2425);
PAINT AQUA (-3000 2425);
DISPLAY INVISIBLE (-3000 2425);
FORCEPROP 1 LAST HDL_POWER GND
J 0
(-3075 2575);
DISPLAY 1.170213 (-3075 2575);
PAINT GREEN (-3075 2575);
DISPLAY INVISIBLE (-3075 2575);
FORCEADD OFFPAGE..5
R 2
(-1175 2825);
FORCEPROP 2 LAST $XR0 73 
J 0
(-986 2825);
DISPLAY 0.638298 (-986 2825);
PAINT MONO (-986 2825);
FORCEPROP 2 LAST CDS_LIB mstr_standard
J 0
(-1175 2825);
PAINT ORANGE (-1175 2825);
DISPLAY INVISIBLE (-1175 2825);
FORCEPROP 1 LAST OFFPAGE TRUE
J 2
(-1500 2700);
PAINT GREEN (-1500 2700);
DISPLAY INVISIBLE (-1500 2700);
FORCEPROP 1 LAST COMMENT_BODY TRUE
J 2
(-1275 2750);
DISPLAY 1.170213 (-1275 2750);
PAINT PEACH (-1275 2750);
DISPLAY INVISIBLE (-1275 2750);
FORCEPROP 2 LAST PATH I83
J 0
(-1000 2900);
DISPLAY 1.021277 (-1000 2900);
PAINT ORANGE (-1000 2900);
DISPLAY INVISIBLE (-1000 2900);
FORCEADD OFFPAGE..5
R 2
(-1175 3175);
FORCEPROP 2 LAST $XR0 39 
J 0
(-986 3175);
DISPLAY 0.638298 (-986 3175);
PAINT MONO (-986 3175);
FORCEPROP 2 LAST CDS_LIB mstr_standard
J 0
(-1175 3175);
PAINT ORANGE (-1175 3175);
DISPLAY INVISIBLE (-1175 3175);
FORCEPROP 1 LAST OFFPAGE TRUE
J 2
(-1500 3050);
PAINT GREEN (-1500 3050);
DISPLAY INVISIBLE (-1500 3050);
FORCEPROP 1 LAST COMMENT_BODY TRUE
J 2
(-1275 3100);
DISPLAY 1.170213 (-1275 3100);
PAINT PEACH (-1275 3100);
DISPLAY INVISIBLE (-1275 3100);
FORCEPROP 2 LAST PATH I84
J 0
(-1000 3250);
DISPLAY 1.021277 (-1000 3250);
PAINT ORANGE (-1000 3250);
DISPLAY INVISIBLE (-1000 3250);
FORCEADD PVCCIO_CPU0..1
(-1200 4775);
FORCEPROP 3 LASTPIN (-1200 4725) SIG_NAME PVCCIO_CPU0\g
J 0
(-1190 4735);
DISPLAY 0.659574 (-1190 4735);
PAINT MONO (-1190 4735);
DISPLAY INVISIBLE (-1190 4735);
FORCEPROP 1 LAST VOLTAGE 1.1V
J 0
(-1245 4732);
DISPLAY 0.340426 (-1245 4732);
PAINT SKYBLUE (-1245 4732);
DISPLAY INVISIBLE (-1245 4732);
FORCEPROP 2 LAST CDS_LIB mstr_symbols
J 0
(-1200 4775);
PAINT ORANGE (-1200 4775);
DISPLAY INVISIBLE (-1200 4775);
FORCEPROP 1 LAST BODY_TYPE PLUMBING
J 0
(-1245 4732);
DISPLAY 0.340426 (-1245 4732);
PAINT GREEN (-1245 4732);
DISPLAY INVISIBLE (-1245 4732);
FORCEPROP 1 LAST PATH I85
J 0
(-1150 4800);
DISPLAY 0.872340 (-1150 4800);
PAINT AQUA (-1150 4800);
DISPLAY INVISIBLE (-1150 4800);
FORCEPROP 1 LAST HDL_POWER PVCCIO_CPU0
J 1
(-1200 4825);
DISPLAY 0.872340 (-1200 4825);
PAINT GREEN (-1200 4825);
DISPLAY INVISIBLE (-1200 4825);
FORCEADD CAD_NOTE..1
(-2000 5050);
FORCEPROP 0 LAST L1 PLACE R4R4 NEAR CPU0, AND R7P20 NEAR CPU1.
J 0
(-2550 4925);
PAINT WHITE (-2550 4925);
FORCEPROP 2 LAST BOM_COST MIO_CHASSIS
J 0
(-2150 5000);
PAINT WHITE (-2150 5000);
DISPLAY INVISIBLE (-2150 5000);
FORCEPROP 2 LAST CDS_LIB mstr_symbols
J 0
(-2000 5050);
PAINT WHITE (-2000 5050);
DISPLAY INVISIBLE (-2000 5050);
FORCEPROP 1 LAST COMMENT_BODY TRUE
J 0
(-1975 5150);
DISPLAY 1.319149 (-1975 5150);
PAINT WHITE (-1975 5150);
DISPLAY INVISIBLE (-1975 5150);
FORCEPROP 2 LAST ROOM ST_SATA
J 0
(-2150 5000);
PAINT WHITE (-2150 5000);
DISPLAY INVISIBLE (-2150 5000);
FORCEADD INTEL_CORP_BPAGE..1
(4250 200);
FORCEPROP 1 LAST CDS_CON_LAST_MODIFIED Fri Jun 16 17:48:39 2017
J 0
(2825 525);
PAINT ORANGE (2825 525);
DISPLAY INVISIBLE (2825 525);
FORCEPROP 1 LAST CUSTOM_TXT_CDS <CURRENT_DESIGN_SHEET> OF <TOTAL_DESIGN_SHEETS>
J 0
(3750 225);
PAINT ORANGE (3750 225);
FORCEPROP 1 LAST CUSTOM_TXT_CDS <CON_LAST_MODIFIED>
J 0
(250 300);
PAINT ORANGE (250 300);
FORCEPROP 2 LAST CUSTOM_TXT_CDS <XR_PAGE_TITLE>
J 0
(-3640 5450);
DISPLAY 0.638298 (-3640 5450);
PAINT PINK (-3640 5450);
DISPLAY INVISIBLE (-3640 5450);
FORCEPROP 1 LAST SCH_TITLE CPU SIDE BAND:PULL-UPS/PULL-DOWNS
J 0
(-3700 250);
DISPLAY 1.212766 (-3700 250);
PAINT YELLOW (-3700 250);
FORCEPROP 2 LAST PAGE_BORDER TRUE
J 0
(-3640 5450);
DISPLAY 0.638298 (-3640 5450);
PAINT PINK (-3640 5450);
DISPLAY INVISIBLE (-3640 5450);
FORCEPROP 2 LAST CDS_LIB mstr_symbols
J 0
(4250 200);
PAINT MONO (4250 200);
DISPLAY INVISIBLE (4250 200);
FORCEPROP 1 LAST COMMENT_BODY TRUE
J 0
(4262 212);
DISPLAY 0.468085 (4262 212);
PAINT PEACH (4262 212);
DISPLAY INVISIBLE (4262 212);
FORCEPROP 2 LAST CDS_XR_PAGE_TITLE CR-97 : @BASEBOARD_FAB2_LIB.BASEBOARD_FAB2(SCH_1):PAGE97
J 0
(-3640 5450);
DISPLAY 0.638298 (-3640 5450);
PAINT PINK (-3640 5450);
DISPLAY INVISIBLE (-3640 5450);
WIRE 16 -1 (-2700 4625)(-2700 4725);
WIRE 16 -1 (-3100 1575)(-3100 1425);
WIRE 16 -1 (-3100 1425)(-2725 1425);
WIRE 16 -1 (-3075 950)(-3075 800);
WIRE 16 -1 (-3075 800)(-2700 800);
WIRE 16 -1 (-3075 2825)(-3075 2475);
WIRE 16 -1 (-3075 3175)(-3075 2825);
WIRE 16 -1 (-2475 2825)(-3075 2825);
WIRE 16 -1 (-2475 3175)(-3075 3175);
WIRE 16 -1 (-1200 4625)(-1200 4725);
WIRE 16 -1 (-3625 4475)(-3625 4300);
WIRE 16 -1 (-3325 4300)(-3625 4300);
WIRE 16 -1 (-3325 4475)(-3625 4475);
WIRE 16 -1 (-3325 4475)(-3325 4300);
WIRE 16 273 (4150 2775)(325 2775);
WIRE 16 -1 (-3600 4450)(-3600 4325);
WIRE 16 -1 (-3600 4325)(-3350 4325);
WIRE 16 -1 (-3350 4450)(-3600 4450);
WIRE 16 -1 (-3350 4450)(-3350 4325);
WIRE 16 273 (250 575)(250 5150);
WIRE 16 -1 (-3350 4225)(-2700 4225);
FORCEPROP 2 LAST SIG_NAME H_CPU0_FAST_WAKE_N
J 0
(-3275 4235);
DISPLAY 0.617021 (-3275 4235);
PAINT ORANGE (-3275 4235);
WIRE 16 -1 (-2700 4425)(-2700 4225);
WIRE 16 -1 (-2700 4225)(-2100 4225);
WIRE 16 273 (150 3950)(-3675 3950);
WIRE 16 273 (150 1950)(-3675 1950);
WIRE 16 -1 (-2525 1425)(-1650 1425);
FORCEPROP 2 LAST SIG_NAME PU_CPU0_TSC_SYNC
J 0
(-2200 1435);
DISPLAY 0.617021 (-2200 1435);
PAINT ORANGE (-2200 1435);
WIRE 16 -1 (-2500 800)(-1625 800);
FORCEPROP 2 LAST SIG_NAME PU_CPU1_TSC_SYNC
J 0
(-2175 810);
DISPLAY 0.617021 (-2175 810);
PAINT ORANGE (-2175 810);
WIRE 16 -1 (-1225 2825)(-2275 2825);
FORCEPROP 0 LAST SIG_NAME PD_CPU1_MCP01_DMON
J 0
(-1810 2835);
DISPLAY 0.617021 (-1810 2835);
PAINT ORANGE (-1810 2835);
WIRE 16 -1 (-2275 3175)(-1225 3175);
FORCEPROP 0 LAST SIG_NAME PD_CPU0_MCP01_DMON
J 0
(-1810 3185);
DISPLAY 0.617021 (-1810 3185);
PAINT ORANGE (-1810 3185);
WIRE 16 -1 (-1200 4225)(-1900 4225);
WIRE 16 -1 (-1200 4425)(-1200 4225);
WIRE 16 -1 (-1200 4225)(-325 4225);
FORCEPROP 2 LAST SIG_NAME H_CPU1_FAST_WAKE_N
J 0
(-1075 4235);
DISPLAY 0.617021 (-1075 4235);
PAINT ORANGE (-1075 4235);
WIRE 16 -1 (-125 4500)(-125 4325);
WIRE 16 -1 (175 4325)(-125 4325);
WIRE 16 -1 (175 4500)(-125 4500);
WIRE 16 -1 (175 4500)(175 4325);
WIRE 16 -1 (-100 4475)(-100 4350);
WIRE 16 -1 (-100 4350)(150 4350);
WIRE 16 -1 (150 4475)(-100 4475);
WIRE 16 -1 (150 4475)(150 4350);
DOT 1 (-2700 4225);
DOT 1 (-1200 4225);
DOT 1 (-3075 2825);
FORCENOTE
TO/FROM
(-3575 4400) 0;
DISPLAY LEFT (-3575 4400);
DISPLAY 0.638298 (-3575 4400);
PAINT PURPLE (-3575 4400);
FORCENOTE
TO/FROM
(-75 4425) 0;
DISPLAY LEFT (-75 4425);
DISPLAY 0.638298 (-75 4425);
PAINT PURPLE (-75 4425);
FORCENOTE
CPU1
(-25 4375) 0;
DISPLAY LEFT (-25 4375);
DISPLAY 0.808511 (-25 4375);
PAINT PURPLE (-25 4375);
FORCENOTE
BOM_COST=PROC_SIDEBAND
(-3675 350) 0;
DISPLAY LEFT (-3675 350);
DISPLAY 1.276596 (-3675 350);
PAINT PURPLE (-3675 350);
FORCENOTE
ROOM=PROC_SIDEBAND
(-3687 433) 0;
DISPLAY LEFT (-3687 433);
DISPLAY 1.276596 (-3687 433);
PAINT PURPLE (-3687 433);
FORCENOTE
CPU0
(-3525 4350) 0;
DISPLAY LEFT (-3525 4350);
DISPLAY 0.808511 (-3525 4350);
PAINT PURPLE (-3525 4350);
QUIT
